G04*
G04 #@! TF.GenerationSoftware,Altium Limited,Altium Designer,23.7.1 (13)*
G04*
G04 Layer_Color=32768*
%FSLAX25Y25*%
%MOIN*%
G70*
G04*
G04 #@! TF.SameCoordinates,AF00DCEB-AC48-4C7C-91EA-99F42E284231*
G04*
G04*
G04 #@! TF.FilePolarity,Positive*
G04*
G01*
G75*
%ADD15C,0.00787*%
D15*
X59785Y-127943D02*
Y-118494D01*
X55060Y-127943D02*
X59785D01*
X55060D02*
Y-118494D01*
X59785D01*
X56044Y-105896D02*
X67068D01*
Y-110226D02*
Y-105896D01*
X56044Y-110226D02*
X67068D01*
X56044D02*
Y-105896D01*
X546902Y-20949D02*
Y19339D01*
X631003D01*
Y-20949D02*
Y19339D01*
X546902Y-20949D02*
X631003D01*
X442815Y-165847D02*
Y-131791D01*
X402854Y-165847D02*
X442815D01*
X402854D02*
Y-131791D01*
X442815D01*
X158268Y-98710D02*
X164567D01*
Y-104419D02*
Y-98710D01*
X158268Y-104419D02*
X164567D01*
X158268D02*
Y-98710D01*
X80984Y2677D02*
X113504D01*
X80984D02*
Y21732D01*
X113504D01*
Y2677D02*
Y21732D01*
X595866Y-230906D02*
X605709D01*
Y-235236D02*
Y-230906D01*
X595866Y-235236D02*
X605709D01*
X595866D02*
Y-230906D01*
X598032Y-188273D02*
Y-183942D01*
Y-188273D02*
X607874D01*
Y-183942D01*
X598032D02*
X607874D01*
X592143Y-217456D02*
X627812D01*
Y-190251D01*
X592143D02*
X627812D01*
X592143Y-217456D02*
Y-190251D01*
X592717Y-152165D02*
Y-147835D01*
Y-152165D02*
X602559D01*
Y-147835D01*
X592717D02*
X602559D01*
X476181Y-270472D02*
Y-261024D01*
Y-270472D02*
X484449D01*
Y-261024D01*
X476181D02*
X484449D01*
X185039Y-98622D02*
X194488D01*
Y-90354D01*
X185039D02*
X194488D01*
X185039Y-98622D02*
Y-90354D01*
X170669Y-82677D02*
X207283D01*
Y4724D01*
X170669D02*
X207283D01*
X170669Y-82677D02*
Y4724D01*
X579528Y-295571D02*
Y-258957D01*
X492126D02*
X579528D01*
X492126Y-295571D02*
Y-258957D01*
Y-295571D02*
X579528D01*
X153579Y-138976D02*
Y-114173D01*
Y-138976D02*
X172871D01*
Y-114173D01*
X153579D02*
X172871D01*
X444410Y-164291D02*
X463465D01*
Y-131772D01*
X444410D02*
X463465D01*
X444410Y-164291D02*
Y-131772D01*
X466929Y-118130D02*
Y-85807D01*
X448032Y-118130D02*
X466929D01*
X448032D02*
Y-85807D01*
X466929D01*
X350787Y-121993D02*
X358946D01*
X350787D02*
Y-117771D01*
X358946D01*
Y-121993D02*
Y-117771D01*
X389079Y-114967D02*
Y-109013D01*
X392229D01*
Y-114967D02*
Y-109013D01*
X389079Y-114967D02*
X392229D01*
X358946Y-115300D02*
Y-111078D01*
X350787D02*
X358946D01*
X350787Y-115300D02*
Y-111078D01*
Y-115300D02*
X358946D01*
X380906Y-116339D02*
Y-107283D01*
X385630D01*
Y-116339D02*
Y-107283D01*
X380906Y-116339D02*
X385630D01*
X434403Y-203486D02*
Y-190215D01*
X422198Y-203486D02*
X434403D01*
X422198D02*
Y-190215D01*
X434403D01*
X44469Y3150D02*
Y22047D01*
Y3150D02*
X76791D01*
Y22047D01*
X44469D02*
X76791D01*
X369756Y-158957D02*
Y-130807D01*
X391409D01*
Y-158957D02*
Y-130807D01*
X369756Y-158957D02*
X391409D01*
X41398Y-61682D02*
Y-40029D01*
Y-61682D02*
X69547D01*
Y-40029D01*
X41398D02*
X69547D01*
X38398Y-22835D02*
Y-14961D01*
X23019D02*
X38398D01*
X23019Y-22835D02*
Y-14961D01*
Y-22835D02*
X38398D01*
X439370Y-125012D02*
X447244D01*
Y-109634D01*
X439370D02*
X447244D01*
X439370Y-125012D02*
Y-109634D01*
X452248Y-129134D02*
Y-121260D01*
Y-129134D02*
X467627D01*
Y-121260D01*
X452248D02*
X467627D01*
X377953Y-115748D02*
Y-107874D01*
X359842D02*
X377953D01*
X359842Y-115748D02*
Y-107874D01*
Y-115748D02*
X377953D01*
X330315Y-144685D02*
X362598D01*
Y-163189D02*
Y-144685D01*
X330315Y-163189D02*
X362598D01*
X330315D02*
Y-144685D01*
X330256Y-124409D02*
X362579D01*
Y-143307D02*
Y-124409D01*
X330256Y-143307D02*
X362579D01*
X330256D02*
Y-124409D01*
X41437Y-33563D02*
Y492D01*
X81398D01*
Y-33563D02*
Y492D01*
X41437Y-33563D02*
X81398D01*
X111831Y-86614D02*
Y-67716D01*
X79508D02*
X111831D01*
X79508Y-86614D02*
Y-67716D01*
Y-86614D02*
X111831D01*
X94291Y-66142D02*
Y-33858D01*
X112795D01*
Y-66142D02*
Y-33858D01*
X94291Y-66142D02*
X112795D01*
X90167Y-65660D02*
Y-57786D01*
X72056D02*
X90167D01*
X72056Y-65660D02*
Y-57786D01*
Y-65660D02*
X90167D01*
X449606Y-78543D02*
Y-74213D01*
Y-78543D02*
X459449D01*
Y-74213D01*
X449606D02*
X459449D01*
X100197Y-94291D02*
Y-89961D01*
X90354D02*
X100197D01*
X90354Y-94291D02*
Y-89961D01*
Y-94291D02*
X100197D01*
X91196Y-97495D02*
X99355D01*
Y-101717D02*
Y-97495D01*
X91196Y-101717D02*
X99355D01*
X91196D02*
Y-97495D01*
X465605Y-78489D02*
X473765D01*
X465605D02*
Y-74267D01*
X473765D01*
Y-78489D02*
Y-74267D01*
X38398Y-13780D02*
Y-5906D01*
X23019D02*
X38398D01*
X23019Y-13780D02*
Y-5906D01*
Y-13780D02*
X38398D01*
X595866Y-218307D02*
X605709D01*
Y-222638D02*
Y-218307D01*
X595866Y-222638D02*
X605709D01*
X595866D02*
Y-218307D01*
X277165Y-199409D02*
Y-191142D01*
X286614D01*
Y-199409D02*
Y-191142D01*
X277165Y-199409D02*
X286614D01*
X178382Y-130905D02*
Y-115945D01*
X186650D01*
Y-130905D02*
Y-115945D01*
X178382Y-130905D02*
X186650D01*
X170221Y-106048D02*
Y-97889D01*
X165999Y-106048D02*
X170221D01*
X165999D02*
Y-97889D01*
X170221D01*
X595866Y-224606D02*
X605709D01*
Y-228937D02*
Y-224606D01*
X595866Y-228937D02*
X605709D01*
X595866D02*
Y-224606D01*
X12819Y-239370D02*
Y-236221D01*
X6866D02*
X12819D01*
X6866Y-239370D02*
Y-236221D01*
Y-239370D02*
X12819D01*
X10063Y-350787D02*
Y-347638D01*
X4110D02*
X10063D01*
X4110Y-350787D02*
Y-347638D01*
Y-350787D02*
X10063D01*
X12598Y-295449D02*
X15748D01*
X12598Y-301402D02*
Y-295449D01*
Y-301402D02*
X15748D01*
Y-295449D01*
X14788Y-194882D02*
Y-191732D01*
X8834D02*
X14788D01*
X8834Y-194882D02*
Y-191732D01*
Y-194882D02*
X14788D01*
X321457Y-244488D02*
Y-235039D01*
Y-244488D02*
X329724D01*
Y-235039D01*
X321457D02*
X329724D01*
X23819Y-4134D02*
Y197D01*
Y-4134D02*
X33661D01*
Y197D01*
X23819D02*
X33661D01*
X23819Y2756D02*
Y7087D01*
Y2756D02*
X33661D01*
Y7087D01*
X23819D02*
X33661D01*
X23819Y9646D02*
Y13976D01*
Y9646D02*
X33661D01*
Y13976D01*
X23819D02*
X33661D01*
X23819Y16535D02*
Y20866D01*
Y16535D02*
X33661D01*
Y20866D01*
X23819D02*
X33661D01*
X146063Y-97052D02*
X150787D01*
X146063Y-106107D02*
Y-97052D01*
Y-106107D02*
X150787D01*
Y-97052D01*
X151038Y-97495D02*
X155261D01*
X151038Y-105655D02*
Y-97495D01*
Y-105655D02*
X155261D01*
Y-97495D01*
X607283Y-258169D02*
Y-255217D01*
Y-258169D02*
X613976D01*
Y-255217D01*
X607283D02*
X613976D01*
X608366Y-249216D02*
X622146D01*
Y-232796D01*
X608366D02*
X622146D01*
X608366Y-249216D02*
Y-232796D01*
X594767Y-304052D02*
Y-295948D01*
Y-304052D02*
X609957D01*
Y-295948D01*
X594767D02*
X609957D01*
X611590Y-304331D02*
Y-301181D01*
Y-304331D02*
X617544D01*
Y-301181D01*
X611590D02*
X617544D01*
X601476Y-293996D02*
Y-290256D01*
X594587D02*
X601476D01*
X594587Y-293996D02*
Y-290256D01*
Y-293996D02*
X601476D01*
X614075Y-262894D02*
Y-259154D01*
X607185D02*
X614075D01*
X607185Y-262894D02*
Y-259154D01*
Y-262894D02*
X614075D01*
X335236Y-297638D02*
Y-288189D01*
Y-297638D02*
X343504D01*
Y-288189D01*
X335236D02*
X343504D01*
X316339Y-298425D02*
Y-288976D01*
Y-298425D02*
X324606D01*
Y-288976D01*
X316339D02*
X324606D01*
X581890Y-77205D02*
Y-51929D01*
X545669D02*
X581890D01*
X545669Y-77205D02*
Y-51929D01*
Y-77205D02*
X581890D01*
X595079Y-86910D02*
X616732D01*
Y-58760D01*
X595079D02*
X616732D01*
X595079Y-86910D02*
Y-58760D01*
X138906Y-135436D02*
Y-121263D01*
X124733Y-135436D02*
X138906D01*
X124733D02*
Y-121263D01*
X138906D01*
M02*
